;LEADER: 12 
;HEADER: 
;CODE  : ASCII 
;FILE  : ncdrill-1-8.tap for board x887571-005_osp.brd ... layers TOP and BOTTOM
;   Holesize 1. = 10.000000 Tolerance = +2.000000/-10.000000 PLATED MILS Quantity = 1600
;   Holesize 2. = 14.000000 Tolerance = +3.000000/-3.000000 PLATED MILS Quantity = 48
;   Holesize 3. = 15.000000 Tolerance = +2.000000/-2.000000 PLATED MILS Quantity = 144
;   Holesize 4. = 20.000000 Tolerance = +2.000000/-2.000000 PLATED MILS Quantity = 538
;   Holesize 5. = 24.000000 Tolerance = +3.000000/-3.000000 PLATED MILS Quantity = 20
;   Holesize 6. = 30.000000 Tolerance = +3.000000/-3.000000 PLATED MILS Quantity = 48
;   Holesize 7. = 33.000000 Tolerance = +2.000000/-2.000000 PLATED MILS Quantity = 2
;   Holesize 8. = 38.000000 Tolerance = +3.000000/-3.000000 PLATED MILS Quantity = 18
;   Holesize 9. = 40.000000 Tolerance = +3.000000/-3.000000 PLATED MILS Quantity = 8
;   Holesize 10. = 41.000000 Tolerance = +2.000000/-2.000000 PLATED MILS Quantity = 44
;   Holesize 11. = 55.000000 Tolerance = +3.000000/-3.000000 PLATED MILS Quantity = 4
;   Holesize 12. = 87.000000 Tolerance = +3.000000/-3.000000 PLATED MILS Quantity = 4
;   Holesize 13. = 138.000000 Tolerance = +5.000000/-5.000000 PLATED MILS Quantity = 6
;   Holesize 14. = 156.000000 Tolerance = +5.000000/-5.000000 PLATED MILS Quantity = 4
;   Holesize 15. = 50.000000 Tolerance = +3.000000/-3.000000 NON_PLATED MILS Quantity = 4
;   Holesize 16. = 61.000000 Tolerance = +3.000000/-3.000000 NON_PLATED MILS Quantity = 4
;   Holesize 17. = 63.000000 Tolerance = +3.000000/-3.000000 NON_PLATED MILS Quantity = 4
;   Holesize 18. = 86.000000 Tolerance = +3.000000/-3.000000 NON_PLATED MILS Quantity = 2
;   Holesize 19. = 125.000000 Tolerance = +2.000000/-1.000000 NON_PLATED MILS Quantity = 3
;   Holesize 20. = 156.000000 Tolerance = +5.000000/-5.000000 NON_PLATED MILS Quantity = 8
%
G90
X-148169Y-010689
X-148669Y-009689
X-148169Y-016689
X-148669Y-015689
X-148169Y-014689
X-148669Y-013689
X-148169Y-012689
X-148669Y-011689
X-148169Y-010189
X-148669Y-009189
X-148169Y-016189
X-148669Y-015189
X-148169Y-014189
X-148669Y-013189
X-148169Y-012189
X-148669Y-011189
X-146169Y-010689
X-146669Y-009689
X-147169Y-016689
X-147669Y-015689
X-147169Y-014689
X-147669Y-013689
X-147169Y-012689
X-147669Y-011689
X-147169Y-010689
X-146169Y-016689
X-146669Y-015689
X-146169Y-014689
X-146669Y-013689
X-146169Y-012689
X-146669Y-011689
X-147669Y-009689
X-146169Y-010189
X-146669Y-009189
X-147169Y-016189
X-147669Y-015189
X-147169Y-014189
X-147669Y-013189
X-147169Y-012189
X-147669Y-011189
X-147169Y-010189
X-146169Y-016189
X-146669Y-015189
X-146169Y-014189
X-146669Y-013189
X-146169Y-012189
X-146669Y-011189
X-147669Y-009189
X-149169Y-007189
X-148669
X-149669
Y-007689
X-149700Y-008170
X-148669Y-016689
X-149704Y-016939
Y-016439
X-147669Y-016689
X-146669
X-149169Y-015689
X-149165Y-015185
X-148669Y-016189
X-149704Y-014939
X-146669Y-016189
X-147169Y-015689
Y-015189
X-148169
Y-015689
X-147669Y-016189
X-146169Y-015689
Y-015189
X-148669Y-014689
Y-014189
X-149169Y-013689
X-149704Y-014439
X-147669Y-014689
X-146669
X-147669Y-014189
X-146669
X-147169Y-013689
X-148169
X-146169
X-149169Y-013189
X-148669Y-012689
Y-012189
X-149704Y-012939
Y-012439
X-147169Y-013189
X-147669Y-012689
X-146669
X-147669Y-012189
X-146669
X-148169Y-013189
X-146169
X-149169Y-011689
Y-011189
X-148669Y-010689
Y-010189
X-149704Y-010439
Y-010939
X-147169Y-011689
Y-011189
X-147669Y-010689
X-146669
X-147669Y-010189
X-146669
X-148169Y-011689
Y-011189
X-146169Y-011689
Y-011189
X-149169Y-009689
Y-009189
X-148669Y-008689
X-149704Y-008939
X-147169Y-009689
Y-009189
X-147669Y-008689
X-146669
X-148169Y-009689
Y-009189
X-146169Y-009689
Y-009189
X-148669Y-008189
X-149169Y-007689
X-147669Y-008189
X-146169Y-008689
R02X-001000
X-146169Y-008189
R02X-001000
X-131673Y-008920
X-132223Y-008840
X-031650Y-011350
X-164949Y-002740
X-144880Y-006770
X-029640Y-011350
X-015240Y-012505
X-162949Y-002770
X-144870Y-005990
X-032160Y-011350
X-059120Y-017970
X-165449Y-002730
X-145180Y-006960
X-015090Y-012110
X-163449Y-002760
X-145150Y-006180
X-144900Y-008030
X-162160Y-006940
X-117030Y-011460
X-161840Y-007160
X-145210Y-008220
X-117610Y-011480
X-037480Y-010570
X-031210Y-011350
X-044860Y-000590
X-164449Y-002750
X-145170Y-006570
X-043677Y-009240
X-043212Y-008708
X-042460Y-001440
X-028650Y-011370
X-016376Y-012858
X-163949Y-002750
X-144880Y-006380
X-132100Y-009485
X-145200Y-007820
X-161850Y-006720
X-120210Y-010320
X-131850Y-000600
X-115440Y-010790
X-130035Y-008850
X-103384Y-012858
X-144890Y-007610
X-130685Y-009500
X-129540Y-001340
X-162160Y-006510
X-064970Y-011720
X-153000Y-012030
X-017510Y-000180
X-017635Y-002720
X-017980Y-004350
X-022540Y-017980
X-025480Y-018000
X-109560Y-017960
X-112470Y-018000
X-105120Y-004410
X-104730Y-000270
X-104729Y-002630
X-028230Y-011370
X-042990Y-007960
X-030850Y-003640
X-030940Y-002510
X-130240Y-008410
X-115420Y-010310
X-117880Y-003480
X-117250Y-003850
X-059661Y-007189
X-146669
X-061161Y-010689
X-061661Y-009689
X-061161Y-016689
X-061661Y-015689
X-061161Y-014689
X-061661Y-013689
X-061161Y-012689
X-061661Y-011689
X-061161Y-010189
X-061661Y-009189
X-061161Y-016189
X-061661Y-015189
X-061161Y-014189
X-061661Y-013189
X-061161Y-012189
X-061661Y-011189
X-059161Y-007689
X-059661Y-008189
Y-007689
X-060161
X-146169
X-146669Y-008189
Y-007689
X-147169
X-061161
X-060661
X-148169
X-147669
X-059161Y-010689
X-059661Y-009689
X-060161Y-016689
X-060661Y-015689
X-060161Y-014689
X-060661Y-013689
X-060161Y-012689
X-060661Y-011689
X-060161Y-010689
X-059161Y-016689
X-059661Y-015689
X-059161Y-014689
X-059661Y-013689
X-059161Y-012689
X-059661Y-011689
X-060661Y-009689
X-059161Y-010189
X-059661Y-009189
X-060161Y-016189
X-060661Y-015189
X-060161Y-014189
X-060661Y-013189
X-060161Y-012189
X-060661Y-011189
X-060161Y-010189
X-059161Y-016189
X-059661Y-015189
X-059161Y-014189
X-059661Y-013189
X-059161Y-012189
X-059661Y-011189
X-060661Y-009189
X-021450Y-017980
X-026520Y-017985
X-024325Y-018221
X-023775Y-018230
X-017030Y-001650
X-017320Y-005240
X-017380Y-004730
X-032130Y-002495
X-032240Y-003100
X-030290Y-003790
X-017020Y-003447
X-032170Y-001363
X-030230Y-002595
X-017981Y-002130
X-030230Y-000445
X-029070Y-000975
X-017901Y000450
X-017050Y-001000
X-029040Y-004320
X-032186Y-000150
X-044196Y-007410
X-044910Y-006084
X-044196Y-005760
Y-006310
Y-005210
Y-004110
Y-003560
X-020610Y-017660
X-020160
X-019690Y-017650
X-110783Y-018230
X-111333Y-018221
X-108460Y-017985
X-113458
X-104130Y-001650
X-119150Y000000
X-117210Y-000540
X-105140Y-002600
X-131056Y-007420
X-131770Y-007270
X-109340Y-009020
X-107300Y-009030
X-109940Y-009020
X-131056Y-005770
Y-006320
Y-005220
X-115970Y-004390
X-104430Y-004766
X-119080Y-002345
X-119190Y-002950
X-115980Y-003310
X-104540Y-003800
X-119120Y-001213
X-117180Y-002695
Y-001625
X-105081Y000260
X-104130Y-001010
X-104510Y-005290
X-131056Y-004120
Y-003570
X-018290Y-002980
X-019030Y-002890
X-037421Y-017800
X-019030Y-000420
X-018320Y-000460
X-037580Y-015400
X-019100Y-005640
X-018590Y-005620
X-037106Y-017900
X-106200Y-002920
X-105490Y-002980
X-110780Y-006820
X-124429Y-017800
X-106190Y-000520
X-105460Y-000510
X-110770Y-006310
X-124639Y-015349
X-106360Y-005660
X-105690Y-005630
X-110770Y-007340
X-124114Y-017900
X-023690Y-017070
X-024030Y-012930
X-024490Y-017070
X-024430Y-012930
X-110698Y-017070
X-111050Y-012900
X-111498Y-017070
X-111450Y-012900
X-061661Y-007189
R02X-000500
Y-007689
X-062662Y-008161
X-046200Y-007350
X-044813Y-008880
X-045363Y-008830
X-044900Y000650
X-043100
X-161000Y-002750
R02Y-000500
X-161500Y-003250
Y-002750
Y-003750
X-159500Y-002750
R02Y-000500
X-160500Y-002750
R02Y-000500
X-160000Y-003250
Y-002750
Y-003750
X-159000Y-002750
R02Y-000500
X-158500
Y-002750
Y-003250
X-158000Y-003750
R02Y000500
X-157000Y-003750
Y-002750
Y-003250
X-157500Y-003750
R02Y000500
X-156500Y-003750
R02Y000500
X-156000Y-003750
R02Y000500
X-155000
R02Y-000500
X-155500Y-002750
R02Y-000500
X-154500Y-002750
R02Y-000500
X-141239Y-004039
R02Y-000500
X-142739Y-004039
R02Y-000500
X-141989Y-004539
Y-004039
Y-005039
X-141239Y-003539
X-142739
X-141989
X-139739Y-005039
R02Y000500
X-138989Y-005039
R02Y000500
X-140489
R02Y-000500
X-139739Y-003539
X-138989
X-140489
X-138239Y-005039
R03Y000500
X-145000Y-017500
R03Y002500
X-143750Y-016250
X-142500Y-008750
X-139100Y-009650
X-142500Y-006250
Y-017500
X-144350Y-009400
X-142450Y-010000
X-141250Y-007500
Y-016250
X-140000Y-017500
Y-015000
X-141200Y-008700
X-140000Y-012500
X-140050Y-008700
X-138750Y-007500
X-140000Y-006250
X-138750Y-016250
R02Y002500
X-137500Y-006250
X-136250Y-007500
X-135000Y-006250
X-133540Y-007500
X-125750Y-004500
Y-002000
X-129350Y-008000
X-123250Y-002000
X-113750Y-001500
X-111150
X-112600Y-000250
X-110000
X-092250Y-000750
X-091000Y-004500
X-089750Y-000750
X-091000Y-002000
Y000500
X-088500Y-004500
R02Y002500
X-087250Y-000750
X-086000Y-004500
R02Y002500
X-083500Y-004500
Y-002000
X-084750Y-000750
X-082250
X-081000Y-002000
Y000500
X-078500Y-002000
X-079750Y-000750
X-078500Y000500
X-077250Y-000750
X-076000Y-004500
R02Y002500
X-073500Y-004500
Y-002000
X-074750Y-000750
X-073500Y000500
X-072250Y-000750
X-071000Y-004500
R02Y002500
X-068500Y-004500
Y-002000
X-069750Y-000750
X-068500Y000500
X-067250Y-000750
X-057750Y-016500
R02Y002500
X-064250Y-001250
X-057750Y-006500
X-056500Y-017750
X-055250Y-016500
Y-014000
X-056500Y-015250
X-065550Y-002550
X-061600
X-064250Y-003750
X-063000
X-064250Y-002550
X-055250Y-006500
X-054000Y-017750
R04Y002500
X-052750Y-016500
R04Y002500
X-051500Y-017750
R03Y002500
X-050250Y-009000
X-051500Y-007750
X-050250Y-006500
X-049000Y-010250
Y-007750
X-057750Y-002500
Y000000
X-056500Y-003750
Y-001250
X-054000Y-003750
X-055250Y-002500
X-054000Y-001250
X-055250Y000000
X-052750Y-002500
Y000000
X-051500Y-003750
Y-001250
X-050250Y-002500
Y000000
X-056500Y001250
R02X002500
X-060250Y-002500
Y000000
X-059000Y-003750
R02Y002500
X-049000Y-003750
R02Y002500
X-047750Y-002500
Y000000
X-046500Y-003750
Y001250
X-044000
X-140750Y001450
R12X002500
X-107000
X-108250
X-104500
R04X002500
X-119950Y-000300
X-099750Y-000750
X-094500
X-097000
X-143200Y-001800
X-140700
X-138250
X-133540Y-003760
X-159000Y-004250
Y-004750
X-158500
Y-004250
X-158000Y-004750
Y-004250
X-157000Y-004750
Y-004250
X-157500Y-004750
Y-004250
X-156500Y-004750
Y-004250
X-154500
Y-004750
X-156000
Y-004250
X-155000
Y-004750
X-155500Y-004250
Y-004750
X-154000
Y-004250
X-153500Y-004750
Y-004250
Y-003250
Y-003750
X-154000Y-003250
Y-003750
X-092200Y001450
X-089750
X-087250
X-084800
X-082250
R06X002500
X-064500
X-092250Y-005750
R04X002500
X-077250
R02X002500
X-137000Y000700
R02X002500
X-138250Y-000050
R02X002500
X-139500Y-000800
R02X002500
X-143489Y-004539
Y-005039
Y-004039
Y-003539
X-091000Y-007000
R03X002500
X-076000
X-091000Y-009500
R03X002500
X-076000
X-083500Y-012000
X-076000
Y-014500
X-091000Y-017000
R02X002500
X-092250Y-008250
R04X002500
X-077250
X-092250Y-010750
R04X002500
X-077250
X-092250Y-013250
R04X002500
X-077250
X-092250Y-015950
R04X002500
X-115150Y-001500
X-042450Y-002650
X-116000Y-011510
X-144910Y-007180
X-102214Y-012296
X-162160Y-006110
X-101767Y-012325
X-145200Y-007400
X-161830Y-006310
X-059161Y-007189
X-146169
X-060161
X-061161
X-060661
X-147169
X-148169
X-147669
X-127264Y-017800
X-117900Y-004050
X-119150Y-003400
X-119100Y-001825
X-117150Y-002175
X-117200Y-001075
X-135670Y-002560
X-140010Y-013155
X-064370Y-012540
X-152436Y-012536
X-062720Y-015130
X-062690Y-014130
X-062870Y-013010
X-062161Y-012189
X-112490Y-017065
X-112488Y-017515
X-109620
X-109628Y-017065
X-044444Y-008071
X-045624Y-008202
X-022612Y-017515
X-022620Y-017065
X-025480Y-017515
X-025480Y-017065
X-019039Y001274
X-046144Y000656
X-044394
X-132484Y-008212
X-131304Y-008081
X-153506Y-002216
R02Y000500
X-152006Y-002216
X-153006
X-152506
X-152006Y-001716
Y-001216
X-153006Y-001716
Y-001216
X-152506Y-001716
Y-001216
X-150506Y-002216
X-151506
X-151006
X-150506Y-001716
Y-001216
X-151506Y-001716
Y-001216
X-151006Y-001716
Y-001216
X-149006Y-002216
X-150006
X-149506
X-149006Y-001716
Y-001216
X-150006Y-001716
Y-001216
X-149506Y-001716
Y-001216
X-147506Y-002216
X-148506
X-148006
X-147506Y-001716
Y-001216
X-148506Y-001716
Y-001216
X-148006Y-001716
Y-001216
X-147006Y-002216
X-146506
X-147006Y-001716
Y-001216
X-146506Y-001716
Y-001216
X-061661Y-016689
Y-016189
Y-014189
Y-014689
Y-012189
Y-012689
Y-010189
Y-010689
Y-008689
Y-008189
X-059661Y-016689
X-060661
Y-016189
X-061161Y-015689
Y-015189
X-060161
Y-015689
X-059661Y-016189
X-061161Y-013689
X-060161
X-059661Y-014189
X-060661
X-059661Y-014689
X-060661
X-061161Y-013189
X-059661Y-012189
X-060661
X-059661Y-012689
X-060661
X-060161Y-013189
X-061161Y-011189
Y-011689
X-059661Y-010189
X-060661
X-059661Y-010689
X-060661
X-060161Y-011189
Y-011689
X-061161Y-009189
Y-009689
X-059661Y-008689
X-060661
X-060161Y-009189
Y-009689
X-060661Y-008189
X-059161Y-015189
Y-015689
Y-013689
Y-013189
Y-011189
Y-011689
Y-009189
Y-009689
X-062157Y-015185
X-062161Y-015689
X-062696Y-016439
Y-016939
Y-010939
Y-010439
Y-008939
X-062161Y-009189
Y-009689
Y-011189
Y-011689
Y-013689
Y-013189
X-007492Y-017150
X-145000Y-016250
R03Y002500
X-143750Y-017500
X-134320Y-008270
X-143650Y-008750
X-143750Y-010000
X-142500Y-016250
X-141850Y-009350
X-143050
X-141250Y-006250
X-140000Y-016250
X-141250Y-017500
X-137380Y-005290
X-141200Y-010050
X-140000Y-011250
Y-007500
X-138750Y-006250
Y-017500
Y-015000
Y-012500
X-137500Y-007500
X-136250Y-006250
X-135060Y-007500
X-133750Y-006250
X-125750Y-005750
X-124500Y-007000
R02Y002500
X-123250Y-005750
X-113750Y-000250
X-112600Y-001500
X-111150Y-000250
X-092250Y-004500
R02Y002500
X-091000Y-005750
X-089750Y-004500
X-091000Y-000750
X-089750Y-002000
Y000500
X-088500Y-005750
Y-000750
X-087250Y-004500
Y000500
X-086000Y-005750
Y-000750
X-083500Y-005750
X-084750Y-004500
R02Y002500
X-082250Y-004500
R02Y002500
X-081000Y-000750
X-078500
X-079750Y-002000
Y000500
X-077250Y-004500
R02Y002500
X-076000Y-005750
Y-000750
X-073500Y-005750
X-074750Y-004500
Y-002000
X-073500Y-000750
X-074750Y000500
X-072250Y-004500
R02Y002500
X-071000Y-000750
X-069750Y-004500
Y-002000
X-068500Y-000750
X-069750Y000500
X-067250Y-004500
R02Y002500
X-057750Y-017750
R02Y002500
X-065550Y-000050
Y-001250
X-055250Y-017750
X-056500Y-016500
X-055250Y-015250
X-056500Y-014000
X-061600Y-001250
X-063000Y-002550
X-065550Y-003750
X-063000Y-001250
X-061600Y-003750
X-056500Y-006500
X-054000Y-016500
R04Y002500
X-052750Y-017750
R04Y002500
X-051500Y-016500
R02Y002500
X-050250Y-010250
Y-007750
X-051500Y-009000
Y-006500
X-049000Y-009000
X-057750Y-003750
Y-001250
X-056500Y-002500
Y000000
X-055250Y-003750
X-054000Y-002500
X-055250Y-001250
X-054000Y000000
X-052750Y-003750
Y-001250
X-051500Y-002500
Y000000
X-050250Y-003750
Y-001250
X-057750Y001250
R03X002500
X-060250Y-003750
R02Y002500
X-059000Y-002500
Y000000
X-049000Y000000
X-047750Y-003750
Y001250
X-046500Y-002500
X-045250Y001250
R12X002500
X-011500
R04X002500
X-101250Y-000750
X-142000Y001450
X-139552Y001405
X-137000Y001450
R11X002500
X-103250
R04X002500
X-026800Y-000050
X-025550Y-001300
X-024300Y-000050
X-110000Y-001500
X-034800Y-001900
Y-004400
X000300Y-007100
X-000950
X-001800Y-017350
X-005950Y-009600
R02Y002500
X-004700Y-008350
R02Y002500
X-004200Y000150
X-003450Y-007100
Y-004600
X-000950Y-009600
X-002200Y-005850
X-000950Y-004600
X-002200Y-003350
X-001700Y000150
X000300Y-010850
Y-005850
Y-003350
X-013900Y-002100
X-012650Y-000850
X-010150Y-003350
X-011400Y-002100
X-010150Y-000850
X-008900Y-002100
X-007650Y-003350
Y-000850
X-003050Y-015850
X-004300Y-014600
X-001800
X-038650Y-004400
Y-001900
X-037400Y-005650
X-036150Y-004400
X-037400Y-003150
X-036150Y-001900
X-033600Y-002800
X-024300Y-002550
X-033600Y-005300
X-032350Y-006550
X-005950Y-002100
X-003450
X-004700Y-000850
X-002200
X-000950Y-002100
X000300Y-000850
X-005950Y-017350
R02Y002500
X-007150Y-015850
Y-013350
X-007050Y-010860
X-000950Y-012000
X-119950Y000540
X-098300Y-000750
X-095750
X-093250
X-163300Y-013550
X-165600Y-013500
X-141950Y-001800
X-139450
X-143500Y000100
X-133250Y-002750
X-143150Y-008100
X-140050Y-009650
X-140625Y-010625
X-139500
X-140625Y-008250
R04X001250
X-138000Y-010625
X-137125Y-011250
X-136375Y-010625
X-142125Y-008125
X-143000Y-007540
X-090950Y001450
X-088500
X-086000
X-083550
X-081000
R06X002500
X-063250
X-061600
X-112881Y-010417
X-109901Y-010418
X-112040Y-012900
X-112480
X-022893Y-010418
X-025472Y-012900
X-025032
X-004250Y-017350
X-005950Y-016100
X-004300Y-015850
X-001800
X-007150Y-014600
X-005950Y-013600
X-003050Y-014600
X-007170Y-012100
X000300Y-012000
X-005950Y-010850
X-000950
X-000935Y-008350
X000300Y-009600
X-005950Y-008350
X-003450
X-004700Y-007100
X-005950Y-005850
R02X002500
X-004700Y-004600
R02X002500
X-011400Y-003350
X-005950
X-003450
X-000950
X-013900Y-000850
X-011400
X-012650Y-002100
X-010150
X-008900Y-000850
X-007650Y-002100
X-005950Y-000850
X-003450
X-004700Y-002100
X-002200
X-000950Y-000850
X000300Y-002100
X-005450Y000150
X-012750Y001250
X-014000
X-010250
R04X002500
X-002200Y-007100
X000300Y-008350
X-038650Y-005650
X-034800Y-005700
X-036150Y-005650
X-023000Y-001350
X-037400Y-004400
X-024300Y-004050
X-038650Y-003150
X-036150
X-025550Y-002550
X-034800Y-003150
X-037400Y-001900
X-033600Y-001550
X-026800Y-001300
X-024300
X-038650Y-000550
X-025550Y-000050
X-023050
X-039000Y001250
R07X002500
X-016500
X-133040Y-007490
X-079750Y-004500
X-081000Y-005750
R02X001250
X-002115Y-008360
X-034240Y-008750
X-035370Y-008760
X-036050Y-008710
X-034785Y-008705
X-028500Y-010310
Y-010740
X-129880Y-003020
X-081000Y-004500
X-078500
X-165850Y-003100
X-041350Y001250
X-132450Y-002696
X-048642Y-002616
X-045442Y-002696
X-138730Y-013320
X-138250Y000700
R03X002500
X-139500Y-000050
R03X002500
X-138250Y-000800
X-135750
X-092250Y-007000
R04X002500
X-081000
R03X001250
X-092250Y-009500
X-089750
X-084750
X-082250
X-077250
X-092250Y-012000
X-082250
X-081000
X-079750
X-077250
X-082250Y-014500
X-081000
X-077250
X-092250Y-017000
R04X002500
X-081000
X-077250
X-091000Y-008250
R03X002500
X-076000
X-091000Y-010750
R03X002500
X-076000
X-091000Y-013250
R04X002500
X-076000
X-091000Y-015950
R03X002500
X-081000Y-015750
X-116000Y-003850
X-123250Y-004500
X-087250Y-002000
Y-009500
X-078550Y-012000
X-123559Y-013205
X-122779
X-126406Y-014195
X-126559Y-014948
X-125613Y-014214
X-127339Y-014948
X-131060Y-004669
X-044200Y-002948
X-014256Y-005606
X-012988Y-009071
X-012978Y-006089
X-013370Y-005606
X-014256Y-007087
Y-008589
X-013330Y-008699
X-013844Y-009139
X-014565Y-010055
X-008770Y-005770
X-009925Y-008589
Y-010085
X-009019Y-010105
X-008657Y-009071
X-008647Y-006089
Y-004592
X-009533
X-009543Y-009071
X-010170Y-007380
X-008647Y-007585
X-013864Y-007600
X-009533Y-007585
X-014510Y-007410
X-101264Y-008589
X-101573Y-010055
X-099996Y-009071
X-100843Y-009140
X-096551Y-009071
X-096933Y-008589
Y-010085
X-096027Y-010105
X-095665Y-009071
X-101264Y-007087
X-101518Y-007410
X-099986Y-007585
X-100872Y-007600
X-096541Y-007585
X-097178Y-007380
X-095655Y-007585
X-101264Y-005606
X-100378
X-099986Y-006089
X-095655
X-096541Y-004592
X-095655
X-014213Y-004129
X-012459Y-004150
X-012660Y-007541
X-008331Y-007536
X-012978Y-007600
X-095325Y-007534
X-100338Y-008699
X-095778Y-005770
X-101286Y-004125
X-099428Y-004089
X-099667Y-007546
X-062161Y-007689
X-061661
X-148669
X-112657Y-013673
Y-014799
X-111713Y-014809
X-110768Y-013673
X-109823
X-110768Y-014809
X-109823
X-112575Y-015748
Y-015288
X-111795
Y-015748
X-111713Y-013673
X-111100Y-011616
X-110640Y-012396
X-111100
X-110640Y-011616
X-123559Y-013665
X-122779
X-125613Y-014674
X-126393
X-126401Y-018594
X-127181
X-126319Y-017800
X-125374
X-124801Y-019220
X-124341
Y-018440
X-124801
X-120392Y-016966
Y-016506
X-121172
Y-016966
X-123484Y-017800
R02X000945
X-126427Y-018107
X-127181Y-018134
X-127339Y-015408
X-126559
X-122609Y-015220
X-121829
X-122609Y-014760
X-121829
X-123784Y-018768
Y-018308
X-123004Y-018768
Y-018308
X-025650Y-013673
X-024705
X-025650Y-014799
X-024705Y-014809
R02X000945
Y-013673
X-023760
X-025567Y-015288
Y-015748
X-024787
Y-015288
X-024092Y-012396
X-023632
X-024092Y-011616
X-023632
X-122697Y-015735
X-123642
X-126476
X-127421
X-040413
X-039469
X-036634
X-035689
X-036476Y-017800
X-034587
X-035531
X-039311
X-040256
X-038366
X-040173Y-018594
Y-018134
X-039393Y-018594
X-039419Y-018107
X-037333Y-018440
Y-019220
X-037793
Y-018440
X-036776Y-018768
Y-018308
X-035996Y-018768
Y-018308
X-033384Y-016966
Y-016506
X-034164
Y-016966
X-039551Y-015408
Y-014948
X-040331Y-015408
Y-014948
X-034821Y-015220
X-035601
X-038605Y-014674
Y-014214
X-039398Y-014195
X-039385Y-014674
X-034821Y-014760
X-035601
X-035771Y-013665
X-036551Y-013205
X-035771
X-036551Y-013665
X-121752Y-015735
X-125532
X-038524
X-034744
X-025873Y-010417
X-036321Y-013435
X-036001
X-036546Y-018538
X-036226
X-035371Y-014990
X-035051
X-033614Y-016736
X-033934
X-038977Y-012722
X-043070Y-006310
X-038960Y-012364
X-042900Y-005760
X-037563Y-018670
Y-018990
X-038835Y-014444
X-039155
X-039623Y-018364
X-039943
X-039781Y-015178
X-040101
X-044196Y-006860
X-042940Y-004110
X-038042Y-014700
X-030940Y-004770
X-043040Y-003560
X-037362Y-012443
X-032150Y-004750
X-033345Y-017495
X-037952Y-018110
X-044280Y-004660
X-045270Y-006900
X-040554Y-018308
X-036791Y-017985
X-037790Y-017793
X-043018Y-005210
X-040554Y-017963
X-123329Y-013435
X-123009
X-123554Y-018538
X-123234
X-122379Y-014990
X-122059
X-120622Y-016736
X-120942
X-125066Y-014048
X-129840Y-006320
X-124902Y-014480
X-129800Y-005840
X-124571Y-018670
Y-018990
X-125843Y-014444
X-126163
X-126631Y-018364
X-126951
X-126789Y-015178
X-127109
X-124886Y-015020
X-131056Y-006870
X-129800Y-004120
X-117890Y-004670
X-123631Y-014039
X-129878Y-005220
X-119100Y-004650
X-120258Y-017630
X-125059Y-017992
X-131120Y-003020
X-131770Y-006020
X-127943Y-018058
X-123799Y-017985
X-129870Y-003570
X-124798Y-017793
X-127686Y-017803
X-023287Y-010420
X-029030Y-000440
X-023602Y-010210
X-029080Y-002600
X-023862Y-012166
Y-011846
X-027810Y-017820
X-023922Y-010420
X-030320Y-004880
X-024232Y-010160
X-027440Y-017820
X-030320Y-004330
X-025179Y-010433
X-030790Y-001363
X-025017Y-015518
X-025337
X-025492Y-010170
X-030250Y-001520
X-024862Y-010176
X-028950Y-003250
X-032180Y-000730
X-024541Y-010424
X-030880Y-000740
X-110295Y-010420
X-115970Y-000575
X-110610Y-010210
X-115870Y-001625
X-110870Y-012166
Y-011846
X-117320Y-004970
X-110930Y-010420
X-117250Y-004400
X-111240Y-010160
X-112187Y-010433
X-117780Y-001210
X-112025Y-015518
X-112345
X-112500Y-010170
X-117895Y-002325
X-111870Y-010176
X-116015Y-002675
X-119236Y-000580
X-111549Y-010424
X-117880Y-000580
X-059161Y-008689
R02X-001000
X-059161Y-008189
R02X-001000
X-032170Y-004200
X-119120Y-004050
M00
X-164591Y-015695
X-165341Y-015995
X-165691Y-016795
X-165391Y-017545
X-164591Y-017895
X-163791Y-017545
X-163491Y-016795
X-163841Y-015995
X-152273Y-014395
X-153023Y-014695
X-153373Y-015495
X-153073Y-016245
X-152273Y-016595
X-151473Y-016245
X-151173Y-015495
X-151523Y-014695
X-104768Y-006774
X-105518Y-007074
X-105868Y-007874
X-105568Y-008624
X-104768Y-008974
X-103968Y-008624
X-103668Y-007874
X-104018Y-007074
X-065264Y-014395
X-066014Y-014695
X-066364Y-015495
X-066064Y-016245
X-065264Y-016595
X-064464Y-016245
X-064164Y-015495
X-064514Y-014695
X-017760Y-006774
X-018510Y-007074
X-018860Y-007874
X-018560Y-008624
X-017760Y-008974
X-016960Y-008624
X-016660Y-007874
X-017010Y-007074
X000689Y-015695
X-000061Y-015995
X-000411Y-016795
X-000111Y-017545
X000689Y-017895
X001489Y-017545
X001789Y-016795
X001439Y-015995
M00
X-094823Y-009858
X-095118Y-009307
X-095413Y-009582
X-095709Y-009858
X-096004Y-009307
X-096299Y-009582
X-096594Y-009858
X-096890Y-009307
X-097185Y-009582
X-095118Y-007811
X-095413Y-008086
X-095709Y-008362
X-094823
X-096890Y-007811
X-096004
X-096299Y-008086
X-096594Y-008362
X-097185Y-008086
X-095118Y-006315
X-095413Y-006590
X-095709Y-006866
X-094823
X-096890Y-006315
X-096004
X-096299Y-006590
X-096594Y-006866
X-097185Y-006590
X-095118Y-004819
X-095413Y-005094
X-095709Y-005370
X-094823
X-096890Y-004819
X-096004
X-096299Y-005094
X-096594Y-005370
X-097185Y-005094
X-099449Y-004819
X-099744Y-005094
X-099154Y-005370
X-099449Y-006315
X-099744Y-006590
X-099154Y-006866
X-099449Y-007811
X-099744Y-008086
X-099449Y-009307
X-099154Y-008362
Y-009858
X-099744Y-009582
X-100039Y-005370
X-100335Y-004819
X-100630Y-005094
X-100925Y-005370
X-100039Y-006866
X-100335Y-006315
X-100630Y-006590
X-100925Y-006866
X-100335Y-007811
X-100630Y-008086
X-100335Y-009307
X-100039Y-008362
X-100925
X-100039Y-009858
X-100630Y-009582
X-100925Y-009858
X-101220Y-004819
X-101516Y-005094
X-101220Y-006315
X-101516Y-006590
X-101220Y-007811
X-101516Y-008086
X-101220Y-009307
X-101516Y-009582
X-007815Y-009858
X-008110Y-009307
X-008406Y-009582
X-008701Y-009858
X-008996Y-009307
X-009291Y-009582
X-009587Y-009858
X-009882Y-009307
X-010177Y-009582
X-008110Y-007811
X-008406Y-008086
X-008701Y-008362
X-007815
X-009882Y-007811
X-008996
X-009291Y-008086
X-009587Y-008362
X-010177Y-008086
X-008110Y-006315
X-008406Y-006590
X-008701Y-006866
X-007815
X-009882Y-006315
X-008996
X-009291Y-006590
X-009587Y-006866
X-010177Y-006590
X-008110Y-004819
X-008406Y-005094
X-008701Y-005370
X-007815
X-009882Y-004819
X-008996
X-009291Y-005094
X-009587Y-005370
X-010177Y-005094
X-012441Y-004819
X-012736Y-005094
X-012146Y-005370
X-012441Y-006315
X-012736Y-006590
X-012146Y-006866
X-012441Y-007811
X-012736Y-008086
X-012441Y-009307
X-012146Y-008362
Y-009858
X-012736Y-009582
X-013031Y-005370
X-013327Y-004819
X-013622Y-005094
X-013917Y-005370
X-013031Y-006866
X-013327Y-006315
X-013622Y-006590
X-013917Y-006866
X-013327Y-007811
X-013622Y-008086
X-013327Y-009307
X-013031Y-008362
X-013917
X-013031Y-009858
X-013622Y-009582
X-013917Y-009858
X-014213Y-004819
X-014508Y-005094
X-014213Y-006315
X-014508Y-006590
X-014213Y-007811
X-014508Y-008086
X-014213Y-009307
X-014508Y-009582
M00
X-154512Y-017819
X-155299Y-017858
X-156087Y-017819
X-156874Y-017858
X-157661Y-017819
X-158449Y-017858
X-159236Y-017819
X-160024Y-017858
X-154512Y-017268
X-155299Y-017307
X-156087Y-017268
X-156874Y-017307
X-157661Y-017268
X-158449Y-017307
X-159236Y-017268
X-160024Y-017307
X-154512Y-016717
X-155299Y-016756
X-156087Y-016717
X-156874Y-016756
X-157661Y-016717
X-158449Y-016756
X-159236Y-016717
X-160024Y-016756
X-154512Y-016165
X-155299Y-016205
X-156087Y-016165
X-156874Y-016205
X-157661Y-016165
X-158449Y-016205
X-159236Y-016165
X-160024Y-016205
X-154512Y-015614
X-155299Y-015654
X-156087Y-015614
X-156874Y-015654
X-157661Y-015614
X-158449Y-015654
X-159236Y-015614
X-160024Y-015654
X-154512Y-015063
X-155299Y-015102
X-156087Y-015063
X-156874Y-015102
X-157661Y-015063
X-158449Y-015102
X-159236Y-015063
X-160024Y-015102
X-154512Y-014512
X-155299Y-014551
X-156087Y-014512
X-156874Y-014551
X-157661Y-014512
X-158449Y-014551
X-159236Y-014512
X-160024Y-014551
X-154512Y-013961
X-155299Y-014000
X-156087Y-013961
X-156874Y-014000
X-157661Y-013961
X-158449Y-014000
X-159236Y-013961
X-160024Y-014000
X-154512Y-013409
X-155299Y-013449
X-156087Y-013409
X-156874Y-013449
X-157661Y-013409
X-158449Y-013449
X-159236Y-013409
X-160024Y-013449
X-160811Y-014512
R02Y000551
Y-015614
Y-015063
Y-016717
Y-016165
Y-017819
Y-017268
X-161598Y-014551
R02Y000551
Y-015654
Y-015102
Y-016756
Y-016205
Y-017858
Y-017307
X-154512Y-011205
R02Y000551
Y-012307
Y-011756
Y-012858
X-155299Y-011244
X-156087Y-011205
X-155299Y-010693
X-156087Y-010654
X-155299Y-010142
X-156087Y-010102
X-155299Y-012346
X-156087Y-012307
X-155299Y-011795
X-156087Y-011756
X-155299Y-012898
X-156087Y-012858
X-156874Y-011244
R02Y000551
Y-012346
Y-011795
Y-012898
X-157661Y-011205
X-158449Y-011244
X-157661Y-010654
X-158449Y-010693
X-157661Y-010102
X-158449Y-010142
X-157661Y-012307
X-158449Y-012346
X-157661Y-011756
X-158449Y-011795
X-157661Y-012858
X-158449Y-012898
X-159236Y-011205
R02Y000551
Y-012307
Y-011756
Y-012858
X-160811Y-010102
R02Y-000551
X-160024Y-011244
R02Y000551
X-160811Y-011756
Y-012307
X-160024Y-012346
Y-011795
X-160811Y-012858
X-160024Y-012898
X-161598Y-010142
R05Y-000551
X-155299Y-009591
R04X-001575
X-115764Y-017858
X-116551Y-017898
X-117339Y-017858
X-118126Y-017898
X-118913Y-017858
X-119701Y-017898
X-115764Y-017307
X-116551Y-017346
X-117339Y-017307
X-118126Y-017346
X-118913Y-017307
X-119701Y-017346
X-115764Y-016756
X-116551Y-016795
X-117339Y-016756
X-118126Y-016795
X-118913Y-016756
X-119701Y-016795
X-115764Y-016205
X-116551Y-016244
X-117339Y-016205
X-118126Y-016244
X-118913Y-016205
X-119701Y-016244
X-115764Y-015654
X-116551Y-015693
X-117339Y-015654
X-118126Y-015693
X-118913Y-015654
X-119701Y-015693
X-115764Y-015102
X-116551Y-015142
X-117339Y-015102
X-118126Y-015142
X-118913Y-015102
X-119701Y-015142
X-115764Y-014551
X-116551Y-014591
X-117339Y-014551
X-118126Y-014591
X-118913Y-014551
X-119701Y-014591
X-115764Y-014000
X-116551Y-014039
X-117339Y-014000
X-118126Y-014039
X-118913Y-014000
X-119701Y-014039
X-115764Y-013449
X-116551Y-013488
X-117339Y-013449
X-118126Y-013488
X-118913Y-013449
X-119701Y-013488
X-116551Y-012937
R02X-001575
X-097512Y-017858
X-098299Y-017898
X-099087Y-017858
X-099874Y-017898
X-100661Y-017858
X-101449Y-017898
X-097512Y-017307
X-098299Y-017346
X-099087Y-017307
X-099874Y-017346
X-100661Y-017307
X-101449Y-017346
X-097512Y-016756
X-098299Y-016795
X-099087Y-016756
X-099874Y-016795
X-100661Y-016756
X-101449Y-016795
X-097512Y-016205
X-098299Y-016244
X-099087Y-016205
X-099874Y-016244
X-100661Y-016205
X-101449Y-016244
X-097512Y-015654
X-098299Y-015693
X-099087Y-015654
X-099874Y-015693
X-100661Y-015654
X-101449Y-015693
X-097512Y-015102
X-098299Y-015142
X-099087Y-015102
X-099874Y-015142
X-100661Y-015102
X-101449Y-015142
X-097512Y-014551
X-098299Y-014591
X-099087Y-014551
X-099874Y-014591
X-100661Y-014551
X-101449Y-014591
X-097512Y-014000
X-098299Y-014039
X-099087Y-014000
X-099874Y-014039
X-100661Y-014000
X-101449Y-014039
X-097512Y-013449
X-098299Y-013488
X-099087Y-013449
X-099874Y-013488
X-100661Y-013449
X-101449Y-013488
X-098299Y-012937
R02X-001575
X-067504Y-017819
X-068291Y-017858
X-069079Y-017819
X-069866Y-017858
X-070654Y-017819
X-071441Y-017858
X-072228Y-017819
X-073016Y-017858
X-067504Y-017268
X-068291Y-017307
X-069079Y-017268
X-069866Y-017307
X-070654Y-017268
X-071441Y-017307
X-072228Y-017268
X-073016Y-017307
X-067504Y-016717
X-068291Y-016756
X-069079Y-016717
X-069866Y-016756
X-070654Y-016717
X-071441Y-016756
X-072228Y-016717
X-073016Y-016756
X-067504Y-016165
X-068291Y-016205
X-069079Y-016165
X-069866Y-016205
X-070654Y-016165
X-071441Y-016205
X-072228Y-016165
X-073016Y-016205
X-067504Y-015614
X-068291Y-015654
X-069079Y-015614
X-069866Y-015654
X-070654Y-015614
X-071441Y-015654
X-072228Y-015614
X-073016Y-015654
X-067504Y-015063
X-068291Y-015102
X-069079Y-015063
X-069866Y-015102
X-070654Y-015063
X-071441Y-015102
X-072228Y-015063
X-073016Y-015102
X-067504Y-014512
X-068291Y-014551
X-069079Y-014512
X-069866Y-014551
X-070654Y-014512
X-071441Y-014551
X-072228Y-014512
X-073016Y-014551
X-067504Y-013961
X-068291Y-014000
X-069079Y-013961
X-069866Y-014000
X-070654Y-013961
X-071441Y-014000
X-072228Y-013961
X-073016Y-014000
X-067504Y-013409
X-068291Y-013449
X-069079Y-013409
X-069866Y-013449
X-070654Y-013409
X-071441Y-013449
X-072228Y-013409
X-073016Y-013449
X-073803Y-014512
R02Y000551
Y-015614
Y-015063
Y-016717
Y-016165
Y-017819
Y-017268
X-074591Y-014551
R02Y000551
Y-015654
Y-015102
Y-016756
Y-016205
Y-017858
Y-017307
X-067504Y-011205
R02Y000551
Y-012307
Y-011756
Y-012858
X-068291Y-011244
X-069079Y-011205
X-068291Y-010693
X-069079Y-010654
X-068291Y-010142
X-069079Y-010102
X-068291Y-012346
X-069079Y-012307
X-068291Y-011795
X-069079Y-011756
X-068291Y-012898
X-069079Y-012858
X-069866Y-011244
R02Y000551
Y-012346
Y-011795
Y-012898
X-070654Y-011205
X-071441Y-011244
X-070654Y-010654
X-071441Y-010693
X-070654Y-010102
X-071441Y-010142
X-070654Y-012307
X-071441Y-012346
X-070654Y-011756
X-071441Y-011795
X-070654Y-012858
X-071441Y-012898
X-072228Y-011205
R02Y000551
Y-012307
Y-011756
Y-012858
X-073803Y-010102
R02Y-000551
X-073016Y-011244
R02Y000551
X-073803Y-011756
Y-012307
X-073016Y-012346
Y-011795
X-073803Y-012858
X-073016Y-012898
X-074591Y-010142
R05Y-000551
X-068291Y-009591
R04X-001575
X-028756Y-017858
X-029543Y-017898
X-030331Y-017858
X-031118Y-017898
X-031906Y-017858
X-032693Y-017898
X-028756Y-017307
X-029543Y-017346
X-030331Y-017307
X-031118Y-017346
X-031906Y-017307
X-032693Y-017346
X-028756Y-016756
X-029543Y-016795
X-030331Y-016756
X-031118Y-016795
X-031906Y-016756
X-032693Y-016795
X-028756Y-016205
X-029543Y-016244
X-030331Y-016205
X-031118Y-016244
X-031906Y-016205
X-032693Y-016244
X-028756Y-015654
X-029543Y-015693
X-030331Y-015654
X-031118Y-015693
X-031906Y-015654
X-032693Y-015693
X-028756Y-015102
X-029543Y-015142
X-030331Y-015102
X-031118Y-015142
X-031906Y-015102
X-032693Y-015142
X-028756Y-014551
X-029543Y-014591
X-030331Y-014551
X-031118Y-014591
X-031906Y-014551
X-032693Y-014591
X-028756Y-014000
X-029543Y-014039
X-030331Y-014000
X-031118Y-014039
X-031906Y-014000
X-032693Y-014039
X-028756Y-013449
X-029543Y-013488
X-030331Y-013449
X-031118Y-013488
X-031906Y-013449
X-032693Y-013488
X-029543Y-012937
R02X-001575
X-010504Y-017858
X-011291Y-017898
X-012079Y-017858
X-012866Y-017898
X-013654Y-017858
X-014441Y-017898
X-010504Y-017307
X-011291Y-017346
X-012079Y-017307
X-012866Y-017346
X-013654Y-017307
X-014441Y-017346
X-010504Y-016756
X-011291Y-016795
X-012079Y-016756
X-012866Y-016795
X-013654Y-016756
X-014441Y-016795
X-010504Y-016205
X-011291Y-016244
X-012079Y-016205
X-012866Y-016244
X-013654Y-016205
X-014441Y-016244
X-010504Y-015654
X-011291Y-015693
X-012079Y-015654
X-012866Y-015693
X-013654Y-015654
X-014441Y-015693
X-010504Y-015102
X-011291Y-015142
X-012079Y-015102
X-012866Y-015142
X-013654Y-015102
X-014441Y-015142
X-010504Y-014551
X-011291Y-014591
X-012079Y-014551
X-012866Y-014591
X-013654Y-014551
X-014441Y-014591
X-010504Y-014000
X-011291Y-014039
X-012079Y-014000
X-012866Y-014039
X-013654Y-014000
X-014441Y-014039
X-010504Y-013449
X-011291Y-013488
X-012079Y-013449
X-012866Y-013488
X-013654Y-013449
X-014441Y-013488
X-011291Y-012937
R02X-001575
M00
X-095413Y-010531
X-097185
X-099744
X-101516
X-093839Y-005094
X-098169
X-102500
X-093839Y000146
X-098169
X-102500
X-008406Y-010531
X-010177
X-012736
X-014508
X-006831Y-005094
X-011161
X-015492
X-006831Y000146
X-011161
X-015492
M00
X-132776Y-012780
X-131988
X-132776Y-013567
X-131988
X-132776Y-014354
X-131988
X-130413Y-012780
X-129626
X-130413Y-013567
X-129626
X-130413Y-014354
X-129626
X-130413Y-015929
X-129626
X-130413Y-016717
X-129626
X-130413Y-017504
X-129626
X-132776Y-015929
X-131988
X-132776Y-016717
X-131988
X-132776Y-017504
X-131988
X-045768Y-012780
X-044980
X-045768Y-013567
X-044980
X-045768Y-014354
X-044980
X-043406Y-012780
X-042618
X-043406Y-013567
X-042618
X-043406Y-014354
X-042618
X-043406Y-015929
X-042618
X-043406Y-016717
X-042618
X-043406Y-017504
X-042618
X-045768Y-015929
X-044980
X-045768Y-016717
X-044980
X-045768Y-017504
X-044980
M00
X-108514Y-012268
X-021506
M00
X-111319Y-015063
X-109429
X-113209
X-108514Y-013252
X-114124
X-108514Y-011283
X-114124
X-108514Y-009433
X-114124
X-024311Y-015063
X-022421
X-026201
X-021506Y-013252
X-027116
X-021506Y-011283
X-027116
X-021506Y-009433
X-027116
M00
X-164900Y-012150
Y-011363
Y-010575
Y-009788
X-079373Y-016185
Y-015398
Y-014610
Y-013823
M00
X-120768Y-015457
Y-011244
Y-007701
R02Y003543
X-122539Y-018409
X-125374
X-128248Y-017228
Y-013016
Y-009472
R02Y003543
X-114124Y-014236
Y-010299
X-108514Y-008331
X-110750
X-112876
X-114124Y-006362
X-108514Y-004394
X-114124Y-002425
X-108514Y-000457
X-111892
X-033760Y-015457
Y-011244
Y-007701
R02Y003543
X-035531Y-018409
X-038366
X-041240Y-017228
Y-013016
Y-009472
R02Y003543
X-027116Y-014236
Y-010299
X-021506Y-008331
X-023742
X-025868
X-027116Y-006362
X-021506Y-004394
X-027116Y-002425
X-021506Y-000457
X-024884
M00
X-078520Y-008310
Y-009964
X-080685Y-008310
Y-009964
M00
X-096004Y-003638
X-100335
X-008996
X-013327
M00
X-164591Y-016795
X-152273Y-015495
X-104768Y-007874
X-065264Y-015495
X-017760Y-007874
X000689Y-016795
M00
X-135689Y-014500
X-105161
X-048681
X-018153
M00
X-148869Y-017894
X-147669Y-006484
X-061861Y-017894
X-060661Y-006484
M00
X-121201Y-014236
X-127815
X-034193
X-040807
M00
X-109429Y-012622
X-113209
X-022421
X-026201
M00
X-131201Y-014945
X-044193
M00
X-141000Y000000
X000000Y000000
X000000Y-013645
M00
X-135689Y-011894
Y-016717
X-105161Y-011894
Y-016717
X-048681Y-011894
Y-016717
X-018153Y-011894
Y-016717
M30
